# T6G (Grand Teton) — schematic netlist excerpt (pin names and nets, part order shuffled) for the footprints in the layout excerpt that follows; sources: Cadence DE-HDL packaged netlist, KiCad conversion of 04192023_DAF0TMB3IC0_F0TG_MB_C_brd_V02_OCP.brd

PR422  Q_RES  2.2 1% CHIP  pkg 0402LF  page 213 : A = PVDDCR_CPU0_P1_PVCC ; B = PVDDCR_CPU0_P1_VCC6
C6077  Q_CAP  0.1UF 25V 10% X7R  pkg 0402  page 177 : A = P1V2_AUX ; B = GND
PC6616_1  Q_CAP  22UF 16V 20% X6S  pkg C0805  page 365 : A = SW_P12V_AUX_P0V9_RETIMER_CPU1_FLT ; B = GND

(kicad_pcb
	(version 20260206)
	(generator "pcbnew")
	(generator_version "10.0")
	(general
		(thickness 1.6)
		(legacy_teardrops no)
	)
	(paper "A4")
	(title_block
		(title "04192023_DAF0TMB3IC0_F0TG_MB_C_brd_V02_OCP.brd")
		(comment 1 "Grand Teton / footprints 6699-6701 of 8354")
	)
	(layers
		(0 "F.Cu" signal "TOP")
		(4 "In1.Cu" signal "GND")
		(6 "In2.Cu" signal "IN1")
		(8 "In3.Cu" signal "GND1")
		(10 "In4.Cu" signal "IN2")
		(12 "In5.Cu" signal "GND2")
		(14 "In6.Cu" signal "IN3")
		(16 "In7.Cu" signal "GND3")
		(18 "In8.Cu" signal "VCC")
		(20 "In9.Cu" signal "VCC1")
		(22 "In10.Cu" signal "GND4")
		(24 "In11.Cu" signal "IN4")
		(26 "In12.Cu" signal "GND5")
		(28 "In13.Cu" signal "IN5")
		(30 "In14.Cu" signal "GND6")
		(32 "In15.Cu" signal "IN6")
		(34 "In16.Cu" signal "GND7")
		(2 "B.Cu" signal "BOTTOM")
		(9 "F.Adhes" user "F.Adhesive")
		(11 "B.Adhes" user "B.Adhesive")
		(13 "F.Paste" user "Package Geometry/Pastemask Top")
		(15 "B.Paste" user "Package Geometry/Pastemask Bottom")
		(5 "F.SilkS" user "Ref Des/Silkscreen Top")
		(7 "B.SilkS" user "Ref Des/Silkscreen Bottom")
		(1 "F.Mask" user "Board Geometry/Soldermask Top")
		(3 "B.Mask" user "Board Geometry/Soldermask Bottom")
		(17 "Dwgs.User" user "User.Drawings")
		(19 "Cmts.User" user "User.Comments")
		(21 "Eco1.User" user "User.Eco1")
		(23 "Eco2.User" user "User.Eco2")
		(25 "Edge.Cuts" user "Board Geometry/Outline")
		(27 "Margin" user)
		(31 "F.CrtYd" user "Package Geometry/Place Bound Top")
		(29 "B.CrtYd" user "Package Geometry/Place Bound Bottom")
		(35 "F.Fab" user "Ref Des/Assembly Top")
		(33 "B.Fab" user "Ref Des/Assembly Bottom")
	)
	(footprint ""
		(layer "B.Cu")
		(at 67.958462 -167.869362 90)
		(property "Reference" "PR422"
			(at 0 0 90)
			(layer "B.SilkS")
			(hide yes)
			(effects
				(font
					(size 1.27 1.27)
				)
				(justify mirror)
			)
		)
		(property "Value" ""
			(at 0 0 90)
			(layer "B.Fab")
			(effects
				(font
					(size 1.27 1.27)
				)
				(justify mirror)
			)
		)
		(duplicate_pad_numbers_are_jumpers no)
		(fp_line
			(start 0.7874 -0.4064)
			(end -0.7874 -0.4064)
			(stroke
				(width 0.1524)
				(type default)
			)
			(layer "B.SilkS")
		)
		(fp_line
			(start -0.7874 -0.4064)
			(end -0.7874 0.4064)
			(stroke
				(width 0.1524)
				(type default)
			)
			(layer "B.SilkS")
		)
		(fp_line
			(start 0.7874 0.4064)
			(end 0.7874 -0.4064)
			(stroke
				(width 0.1524)
				(type default)
			)
			(layer "B.SilkS")
		)
		(fp_line
			(start -0.7874 0.4064)
			(end 0.7874 0.4064)
			(stroke
				(width 0.1524)
				(type default)
			)
			(layer "B.SilkS")
		)
		(fp_line
			(start 0.67945 -0.305054)
			(end 0.12065 -0.305054)
			(stroke
				(width 0.1)
				(type default)
			)
			(layer "B.Fab")
		)
		(fp_line
			(start 0.12065 -0.305054)
			(end 0.12065 -0.2794)
			(stroke
				(width 0.1)
				(type default)
			)
			(layer "B.Fab")
		)
		(fp_line
			(start -0.12065 -0.3048)
			(end -0.67945 -0.3048)
			(stroke
				(width 0.1)
				(type default)
			)
			(layer "B.Fab")
		)
		(fp_line
			(start -0.67945 -0.3048)
			(end -0.67945 0.3048)
			(stroke
				(width 0.1)
				(type default)
			)
			(layer "B.Fab")
		)
		(fp_line
			(start 0.12065 -0.2794)
			(end -0.12065 -0.2794)
			(stroke
				(width 0.1)
				(type default)
			)
			(layer "B.Fab")
		)
		(fp_line
			(start -0.12065 -0.2794)
			(end -0.12065 -0.3048)
			(stroke
				(width 0.1)
				(type default)
			)
			(layer "B.Fab")
		)
		(fp_line
			(start 0.12065 0.2794)
			(end 0.12065 0.3048)
			(stroke
				(width 0.1)
				(type default)
			)
			(layer "B.Fab")
		)
		(fp_line
			(start -0.120396 0.2794)
			(end 0.12065 0.2794)
			(stroke
				(width 0.1)
				(type default)
			)
			(layer "B.Fab")
		)
		(fp_line
			(start 0.67945 0.3048)
			(end 0.67945 -0.305054)
			(stroke
				(width 0.1)
				(type default)
			)
			(layer "B.Fab")
		)
		(fp_line
			(start 0.12065 0.3048)
			(end 0.67945 0.3048)
			(stroke
				(width 0.1)
				(type default)
			)
			(layer "B.Fab")
		)
		(fp_line
			(start -0.120396 0.3048)
			(end -0.120396 0.2794)
			(stroke
				(width 0.1)
				(type default)
			)
			(layer "B.Fab")
		)
		(fp_line
			(start -0.67945 0.3048)
			(end -0.120396 0.3048)
			(stroke
				(width 0.1)
				(type default)
			)
			(layer "B.Fab")
		)
		(pad "1" smd circle
			(at 0.40005 0 270)
			(size 0 0)
			(layers "B.Cu" "B.Mask" "B.Paste")
			(net "PVDDCR_CPU0_P1_PVCC")
		)
		(pad "2" smd circle
			(at -0.40005 0 270)
			(size 0 0)
			(layers "B.Cu" "B.Mask" "B.Paste")
			(net "PVDDCR_CPU0_P1_VCC6")
		)
	)
	(footprint ""
		(layer "B.Cu")
		(at 18.039588 -399.209006)
		(property "Reference" "PC6616_1"
			(at 0 0 0)
			(layer "B.SilkS")
			(hide yes)
			(effects
				(font
					(size 1.27 1.27)
				)
				(justify mirror)
			)
		)
		(property "Value" ""
			(at 0 0 0)
			(layer "B.Fab")
			(effects
				(font
					(size 1.27 1.27)
				)
				(justify mirror)
			)
		)
		(duplicate_pad_numbers_are_jumpers no)
		(fp_line
			(start -1.524 -0.762)
			(end -1.524 0.762)
			(stroke
				(width 0.1524)
				(type default)
			)
			(layer "B.SilkS")
		)
		(fp_line
			(start -1.524 0.762)
			(end 1.524 0.762)
			(stroke
				(width 0.1524)
				(type default)
			)
			(layer "B.SilkS")
		)
		(fp_line
			(start 1.524 -0.762)
			(end -1.524 -0.762)
			(stroke
				(width 0.1524)
				(type default)
			)
			(layer "B.SilkS")
		)
		(fp_line
			(start 1.524 0.762)
			(end 1.524 -0.762)
			(stroke
				(width 0.1524)
				(type default)
			)
			(layer "B.SilkS")
		)
		(fp_line
			(start -1.1049 -0.724916)
			(end 1.1049 -0.724916)
			(stroke
				(width 0.1)
				(type default)
			)
			(layer "B.Fab")
		)
		(fp_line
			(start -1.1049 0.724916)
			(end -1.1049 -0.724916)
			(stroke
				(width 0.1)
				(type default)
			)
			(layer "B.Fab")
		)
		(fp_line
			(start 1.1049 -0.724916)
			(end 1.1049 0.724916)
			(stroke
				(width 0.1)
				(type default)
			)
			(layer "B.Fab")
		)
		(fp_line
			(start 1.1049 0.724916)
			(end -1.1049 0.724916)
			(stroke
				(width 0.1)
				(type default)
			)
			(layer "B.Fab")
		)
		(pad "1" smd rect
			(at 0.889 0)
			(size 1.016 1.27)
			(layers "B.Cu" "B.Mask" "B.Paste")
			(net "SW_P12V_AUX_P0V9_RETIMER_CPU1_FLT")
		)
		(pad "2" smd rect
			(at -0.889 0)
			(size 1.016 1.27)
			(layers "B.Cu" "B.Mask" "B.Paste")
			(net "GND")
		)
	)
	(footprint ""
		(layer "B.Cu")
		(at 128.172972 -41.947592 -90)
		(property "Reference" "C6077"
			(at 0 0 90)
			(layer "B.SilkS")
			(hide yes)
			(effects
				(font
					(size 1.27 1.27)
				)
				(justify mirror)
			)
		)
		(property "Value" ""
			(at 0 0 90)
			(layer "B.Fab")
			(effects
				(font
					(size 1.27 1.27)
				)
				(justify mirror)
			)
		)
		(duplicate_pad_numbers_are_jumpers no)
		(fp_line
			(start -0.7874 0.4064)
			(end 0.7874 0.4064)
			(stroke
				(width 0.1524)
				(type default)
			)
			(layer "B.SilkS")
		)
		(fp_line
			(start 0.7874 0.4064)
			(end 0.7874 -0.4064)
			(stroke
				(width 0.1524)
				(type default)
			)
			(layer "B.SilkS")
		)
		(fp_line
			(start -0.7874 -0.4064)
			(end -0.7874 0.4064)
			(stroke
				(width 0.1524)
				(type default)
			)
			(layer "B.SilkS")
		)
		(fp_line
			(start 0.7874 -0.4064)
			(end -0.7874 -0.4064)
			(stroke
				(width 0.1524)
				(type default)
			)
			(layer "B.SilkS")
		)
		(fp_line
			(start -0.67945 0.3048)
			(end -0.120396 0.3048)
			(stroke
				(width 0.1)
				(type default)
			)
			(layer "B.Fab")
		)
		(fp_line
			(start -0.120396 0.3048)
			(end -0.120396 0.2794)
			(stroke
				(width 0.1)
				(type default)
			)
			(layer "B.Fab")
		)
		(fp_line
			(start 0.12065 0.3048)
			(end 0.67945 0.3048)
			(stroke
				(width 0.1)
				(type default)
			)
			(layer "B.Fab")
		)
		(fp_line
			(start 0.67945 0.3048)
			(end 0.67945 -0.305054)
			(stroke
				(width 0.1)
				(type default)
			)
			(layer "B.Fab")
		)
		(fp_line
			(start -0.120396 0.2794)
			(end 0.12065 0.2794)
			(stroke
				(width 0.1)
				(type default)
			)
			(layer "B.Fab")
		)
		(fp_line
			(start 0.12065 0.2794)
			(end 0.12065 0.3048)
			(stroke
				(width 0.1)
				(type default)
			)
			(layer "B.Fab")
		)
		(fp_line
			(start -0.12065 -0.2794)
			(end -0.12065 -0.3048)
			(stroke
				(width 0.1)
				(type default)
			)
			(layer "B.Fab")
		)
		(fp_line
			(start 0.12065 -0.2794)
			(end -0.12065 -0.2794)
			(stroke
				(width 0.1)
				(type default)
			)
			(layer "B.Fab")
		)
		(fp_line
			(start -0.67945 -0.3048)
			(end -0.67945 0.3048)
			(stroke
				(width 0.1)
				(type default)
			)
			(layer "B.Fab")
		)
		(fp_line
			(start -0.12065 -0.3048)
			(end -0.67945 -0.3048)
			(stroke
				(width 0.1)
				(type default)
			)
			(layer "B.Fab")
		)
		(fp_line
			(start 0.12065 -0.305054)
			(end 0.12065 -0.2794)
			(stroke
				(width 0.1)
				(type default)
			)
			(layer "B.Fab")
		)
		(fp_line
			(start 0.67945 -0.305054)
			(end 0.12065 -0.305054)
			(stroke
				(width 0.1)
				(type default)
			)
			(layer "B.Fab")
		)
		(pad "1" smd circle
			(at 0.40005 0 90)
			(size 0 0)
			(layers "B.Cu" "B.Mask" "B.Paste")
			(net "P1V2_AUX")
		)
		(pad "2" smd circle
			(at -0.40005 0 90)
			(size 0 0)
			(layers "B.Cu" "B.Mask" "B.Paste")
			(net "GND")
		)
	)
)
